# T6G (Grand Teton) — schematic netlist excerpt (pin names and nets, part order shuffled) for the footprints in the layout excerpt that follows; sources: Cadence DE-HDL packaged netlist, KiCad conversion of 04192023_DAF0TMB3IC0_F0TG_MB_C_brd_V02_OCP.brd

R313  Q_RES  1K 1% CHIP  pkg 0402LF  page 108 : A = PWRGD_CHK_CPU1_DIMM ; B = PWRGD_CHGL_CPU1

DB12  TDR_3P  EMPTY  pkg TH2  page 260
  GND  = T1_GND
  IO1  = TDR_SE_50_OHM_BOT
  IO2  = TDR_SE_50_OHM_BOT

PR351  Q_RES  0 5% CHIP  pkg 0402LF  page 195 : A = PVDDCR_CPU0_P0_VOS4 ; B = PVDDCR_CPU0_P0

(kicad_pcb
	(version 20260206)
	(generator "pcbnew")
	(generator_version "10.0")
	(general
		(thickness 1.6)
		(legacy_teardrops no)
	)
	(paper "A4")
	(title_block
		(title "04192023_DAF0TMB3IC0_F0TG_MB_C_brd_V02_OCP.brd")
		(comment 1 "Grand Teton / footprints 5386-5388 of 8354")
	)
	(layers
		(0 "F.Cu" signal "TOP")
		(4 "In1.Cu" signal "GND")
		(6 "In2.Cu" signal "IN1")
		(8 "In3.Cu" signal "GND1")
		(10 "In4.Cu" signal "IN2")
		(12 "In5.Cu" signal "GND2")
		(14 "In6.Cu" signal "IN3")
		(16 "In7.Cu" signal "GND3")
		(18 "In8.Cu" signal "VCC")
		(20 "In9.Cu" signal "VCC1")
		(22 "In10.Cu" signal "GND4")
		(24 "In11.Cu" signal "IN4")
		(26 "In12.Cu" signal "GND5")
		(28 "In13.Cu" signal "IN5")
		(30 "In14.Cu" signal "GND6")
		(32 "In15.Cu" signal "IN6")
		(34 "In16.Cu" signal "GND7")
		(2 "B.Cu" signal "BOTTOM")
		(9 "F.Adhes" user "F.Adhesive")
		(11 "B.Adhes" user "B.Adhesive")
		(13 "F.Paste" user "Package Geometry/Pastemask Top")
		(15 "B.Paste" user "Package Geometry/Pastemask Bottom")
		(5 "F.SilkS" user "Ref Des/Silkscreen Top")
		(7 "B.SilkS" user "Ref Des/Silkscreen Bottom")
		(1 "F.Mask" user "Board Geometry/Soldermask Top")
		(3 "B.Mask" user "Board Geometry/Soldermask Bottom")
		(17 "Dwgs.User" user "User.Drawings")
		(19 "Cmts.User" user "User.Comments")
		(21 "Eco1.User" user "User.Eco1")
		(23 "Eco2.User" user "User.Eco2")
		(25 "Edge.Cuts" user "Board Geometry/Outline")
		(27 "Margin" user)
		(31 "F.CrtYd" user "Package Geometry/Place Bound Top")
		(29 "B.CrtYd" user "Package Geometry/Place Bound Bottom")
		(35 "F.Fab" user "Ref Des/Assembly Top")
		(33 "B.Fab" user "Ref Des/Assembly Bottom")
	)
	(footprint ""
		(layer "B.Cu")
		(at 393.070588 -180.078634 90)
		(property "Reference" "PR351"
			(at 0 0 90)
			(layer "B.SilkS")
			(hide yes)
			(effects
				(font
					(size 1.27 1.27)
				)
				(justify mirror)
			)
		)
		(property "Value" ""
			(at 0 0 90)
			(layer "B.Fab")
			(effects
				(font
					(size 1.27 1.27)
				)
				(justify mirror)
			)
		)
		(duplicate_pad_numbers_are_jumpers no)
		(fp_line
			(start 0.7874 -0.4064)
			(end -0.7874 -0.4064)
			(stroke
				(width 0.1524)
				(type default)
			)
			(layer "B.SilkS")
		)
		(fp_line
			(start -0.7874 -0.4064)
			(end -0.7874 0.4064)
			(stroke
				(width 0.1524)
				(type default)
			)
			(layer "B.SilkS")
		)
		(fp_line
			(start 0.7874 0.4064)
			(end 0.7874 -0.4064)
			(stroke
				(width 0.1524)
				(type default)
			)
			(layer "B.SilkS")
		)
		(fp_line
			(start -0.7874 0.4064)
			(end 0.7874 0.4064)
			(stroke
				(width 0.1524)
				(type default)
			)
			(layer "B.SilkS")
		)
		(fp_line
			(start 0.67945 -0.305054)
			(end 0.12065 -0.305054)
			(stroke
				(width 0.1)
				(type default)
			)
			(layer "B.Fab")
		)
		(fp_line
			(start 0.12065 -0.305054)
			(end 0.12065 -0.2794)
			(stroke
				(width 0.1)
				(type default)
			)
			(layer "B.Fab")
		)
		(fp_line
			(start -0.12065 -0.3048)
			(end -0.67945 -0.3048)
			(stroke
				(width 0.1)
				(type default)
			)
			(layer "B.Fab")
		)
		(fp_line
			(start -0.67945 -0.3048)
			(end -0.67945 0.3048)
			(stroke
				(width 0.1)
				(type default)
			)
			(layer "B.Fab")
		)
		(fp_line
			(start 0.12065 -0.2794)
			(end -0.12065 -0.2794)
			(stroke
				(width 0.1)
				(type default)
			)
			(layer "B.Fab")
		)
		(fp_line
			(start -0.12065 -0.2794)
			(end -0.12065 -0.3048)
			(stroke
				(width 0.1)
				(type default)
			)
			(layer "B.Fab")
		)
		(fp_line
			(start 0.12065 0.2794)
			(end 0.12065 0.3048)
			(stroke
				(width 0.1)
				(type default)
			)
			(layer "B.Fab")
		)
		(fp_line
			(start -0.120396 0.2794)
			(end 0.12065 0.2794)
			(stroke
				(width 0.1)
				(type default)
			)
			(layer "B.Fab")
		)
		(fp_line
			(start 0.67945 0.3048)
			(end 0.67945 -0.305054)
			(stroke
				(width 0.1)
				(type default)
			)
			(layer "B.Fab")
		)
		(fp_line
			(start 0.12065 0.3048)
			(end 0.67945 0.3048)
			(stroke
				(width 0.1)
				(type default)
			)
			(layer "B.Fab")
		)
		(fp_line
			(start -0.120396 0.3048)
			(end -0.120396 0.2794)
			(stroke
				(width 0.1)
				(type default)
			)
			(layer "B.Fab")
		)
		(fp_line
			(start -0.67945 0.3048)
			(end -0.120396 0.3048)
			(stroke
				(width 0.1)
				(type default)
			)
			(layer "B.Fab")
		)
		(pad "1" smd circle
			(at 0.40005 0 270)
			(size 0 0)
			(layers "B.Cu" "B.Mask" "B.Paste")
			(net "PVDDCR_CPU0_P0_VOS4")
		)
		(pad "2" smd circle
			(at -0.40005 0 270)
			(size 0 0)
			(layers "B.Cu" "B.Mask" "B.Paste")
			(net "PVDDCR_CPU0_P0")
		)
	)
	(footprint ""
		(layer "B.Cu")
		(at 191.64046 -190.821564)
		(property "Reference" "R313"
			(at 0 0 0)
			(layer "B.SilkS")
			(hide yes)
			(effects
				(font
					(size 1.27 1.27)
				)
				(justify mirror)
			)
		)
		(property "Value" ""
			(at 0 0 0)
			(layer "B.Fab")
			(effects
				(font
					(size 1.27 1.27)
				)
				(justify mirror)
			)
		)
		(duplicate_pad_numbers_are_jumpers no)
		(fp_line
			(start -0.7874 -0.4064)
			(end -0.7874 0.4064)
			(stroke
				(width 0.1524)
				(type default)
			)
			(layer "B.SilkS")
		)
		(fp_line
			(start -0.7874 0.4064)
			(end 0.7874 0.4064)
			(stroke
				(width 0.1524)
				(type default)
			)
			(layer "B.SilkS")
		)
		(fp_line
			(start 0.7874 -0.4064)
			(end -0.7874 -0.4064)
			(stroke
				(width 0.1524)
				(type default)
			)
			(layer "B.SilkS")
		)
		(fp_line
			(start 0.7874 0.4064)
			(end 0.7874 -0.4064)
			(stroke
				(width 0.1524)
				(type default)
			)
			(layer "B.SilkS")
		)
		(fp_line
			(start -0.67945 -0.3048)
			(end -0.67945 0.3048)
			(stroke
				(width 0.1)
				(type default)
			)
			(layer "B.Fab")
		)
		(fp_line
			(start -0.67945 0.3048)
			(end -0.120396 0.3048)
			(stroke
				(width 0.1)
				(type default)
			)
			(layer "B.Fab")
		)
		(fp_line
			(start -0.12065 -0.3048)
			(end -0.67945 -0.3048)
			(stroke
				(width 0.1)
				(type default)
			)
			(layer "B.Fab")
		)
		(fp_line
			(start -0.12065 -0.2794)
			(end -0.12065 -0.3048)
			(stroke
				(width 0.1)
				(type default)
			)
			(layer "B.Fab")
		)
		(fp_line
			(start -0.120396 0.2794)
			(end 0.12065 0.2794)
			(stroke
				(width 0.1)
				(type default)
			)
			(layer "B.Fab")
		)
		(fp_line
			(start -0.120396 0.3048)
			(end -0.120396 0.2794)
			(stroke
				(width 0.1)
				(type default)
			)
			(layer "B.Fab")
		)
		(fp_line
			(start 0.12065 -0.305054)
			(end 0.12065 -0.2794)
			(stroke
				(width 0.1)
				(type default)
			)
			(layer "B.Fab")
		)
		(fp_line
			(start 0.12065 -0.2794)
			(end -0.12065 -0.2794)
			(stroke
				(width 0.1)
				(type default)
			)
			(layer "B.Fab")
		)
		(fp_line
			(start 0.12065 0.2794)
			(end 0.12065 0.3048)
			(stroke
				(width 0.1)
				(type default)
			)
			(layer "B.Fab")
		)
		(fp_line
			(start 0.12065 0.3048)
			(end 0.67945 0.3048)
			(stroke
				(width 0.1)
				(type default)
			)
			(layer "B.Fab")
		)
		(fp_line
			(start 0.67945 -0.305054)
			(end 0.12065 -0.305054)
			(stroke
				(width 0.1)
				(type default)
			)
			(layer "B.Fab")
		)
		(fp_line
			(start 0.67945 0.3048)
			(end 0.67945 -0.305054)
			(stroke
				(width 0.1)
				(type default)
			)
			(layer "B.Fab")
		)
		(pad "1" smd circle
			(at 0.40005 0 180)
			(size 0 0)
			(layers "B.Cu" "B.Mask" "B.Paste")
			(net "PWRGD_CHK_CPU1_DIMM")
		)
		(pad "2" smd circle
			(at -0.40005 0 180)
			(size 0 0)
			(layers "B.Cu" "B.Mask" "B.Paste")
			(net "PWRGD_CHGL_CPU1")
		)
	)
	(footprint ""
		(layer "B.Cu")
		(at 527.336512 -107.699302 180)
		(property "Reference" "DB12"
			(at 2.546096 -8.857742 270)
			(unlocked yes)
			(layer "B.SilkS")
			(effects
				(font
					(size 0.7874 0.5842)
					(thickness 0.1524)
				)
				(justify left mirror)
			)
		)
		(property "Value" ""
			(at 0 0 0)
			(layer "B.Fab")
			(effects
				(font
					(size 1.27 1.27)
				)
				(justify mirror)
			)
		)
		(duplicate_pad_numbers_are_jumpers no)
		(fp_line
			(start 3.330702 -4.771136)
			(end -3.330702 -4.771136)
			(stroke
				(width 0.1524)
				(type default)
			)
			(layer "B.SilkS")
		)
		(fp_line
			(start 0 4.011168)
			(end 3.330702 -4.771136)
			(stroke
				(width 0.1524)
				(type default)
			)
			(layer "B.SilkS")
		)
		(fp_line
			(start -3.330702 -4.771136)
			(end 0 4.011168)
			(stroke
				(width 0.1524)
				(type default)
			)
			(layer "B.SilkS")
		)
		(fp_line
			(start 3.330702 -4.771136)
			(end -3.330702 -4.771136)
			(stroke
				(width 0.1)
				(type default)
			)
			(layer "B.Fab")
		)
		(fp_line
			(start 0 4.011168)
			(end 3.330702 -4.771136)
			(stroke
				(width 0.1)
				(type default)
			)
			(layer "B.Fab")
		)
		(fp_line
			(start -3.330702 -4.771136)
			(end 0 4.011168)
			(stroke
				(width 0.1)
				(type default)
			)
			(layer "B.Fab")
		)
		(pad "1" thru_hole circle
			(at 0 0)
			(size 2.159 2.159)
			(drill 1.7018)
			(layers "*.Cu" "*.Mask")
			(remove_unused_layers no)
			(net "T1_GND")
			(clearance 0.0254)
			(thermal_gap 0.0254)
		)
		(pad "2" thru_hole circle
			(at 1.27 -3.348736)
			(size 2.159 2.159)
			(drill 1.7018)
			(layers "*.Cu" "*.Mask")
			(remove_unused_layers no)
			(net "TDR_SE_50_OHM_BOT")
			(clearance 0.0254)
			(thermal_gap 0.0254)
		)
		(pad "3" thru_hole circle
			(at -1.27 -3.348736)
			(size 2.159 2.159)
			(drill 1.7018)
			(layers "*.Cu" "*.Mask")
			(remove_unused_layers no)
			(net "TDR_SE_50_OHM_BOT")
			(clearance 0.0254)
			(thermal_gap 0.0254)
		)
	)
)
